(kicad_pcb
	(version 20260206)
	(generator "pcbnew")
	(generator_version "10.0")
	(general
		(thickness 1.6)
		(legacy_teardrops no)
	)
	(paper "A4")
	(title_block
		(title "03242023_DA0F0TMBIJ0_F0T_Motherboard_J_brd_V01_OCP.brd")
		(comment 1 "Grand Teton / footprints 2113-2118 of 6105")
	)
	(layers
		(0 "F.Cu" signal "TOP")
		(4 "In1.Cu" signal "GND")
		(6 "In2.Cu" signal "IN1")
		(8 "In3.Cu" signal "GND1")
		(10 "In4.Cu" signal "IN2")
		(12 "In5.Cu" signal "GND2")
		(14 "In6.Cu" signal "IN3")
		(16 "In7.Cu" signal "GND3")
		(18 "In8.Cu" signal "VCC")
		(20 "In9.Cu" signal "VCC1")
		(22 "In10.Cu" signal "GND4")
		(24 "In11.Cu" signal "IN4")
		(26 "In12.Cu" signal "GND5")
		(28 "In13.Cu" signal "IN5")
		(30 "In14.Cu" signal "GND6")
		(32 "In15.Cu" signal "IN6")
		(34 "In16.Cu" signal "GND7")
		(2 "B.Cu" signal "BOTTOM")
		(9 "F.Adhes" user "F.Adhesive")
		(11 "B.Adhes" user "B.Adhesive")
		(13 "F.Paste" user "Package Geometry/Pastemask Top")
		(15 "B.Paste" user "Package Geometry/Pastemask Bottom")
		(5 "F.SilkS" user "Ref Des/Silkscreen Top")
		(7 "B.SilkS" user "Ref Des/Silkscreen Bottom")
		(1 "F.Mask" user "Board Geometry/Soldermask Top")
		(3 "B.Mask" user "Board Geometry/Soldermask Bottom")
		(17 "Dwgs.User" user "User.Drawings")
		(19 "Cmts.User" user "User.Comments")
		(21 "Eco1.User" user "User.Eco1")
		(23 "Eco2.User" user "User.Eco2")
		(25 "Edge.Cuts" user "Board Geometry/Outline")
		(27 "Margin" user)
		(31 "F.CrtYd" user "Package Geometry/Place Bound Top")
		(29 "B.CrtYd" user "Package Geometry/Place Bound Bottom")
		(35 "F.Fab" user "Ref Des/Assembly Top")
		(33 "B.Fab" user "Ref Des/Assembly Bottom")
	)
	(footprint ""
		(layer "F.Cu")
		(at 126.534926 -119.810784 -90)
		(property "Reference" "R2969"
			(at 0 0 270)
			(layer "F.SilkS")
			(hide yes)
			(effects
				(font
					(size 1.27 1.27)
				)
			)
		)
		(property "Value" ""
			(at 0 0 270)
			(layer "F.Fab")
			(effects
				(font
					(size 1.27 1.27)
				)
			)
		)
		(duplicate_pad_numbers_are_jumpers no)
		(fp_line
			(start -0.7874 0.4064)
			(end -0.7874 -0.4064)
			(stroke
				(width 0.1524)
				(type default)
			)
			(layer "F.SilkS")
		)
		(fp_line
			(start 0.7874 0.4064)
			(end -0.7874 0.4064)
			(stroke
				(width 0.1524)
				(type default)
			)
			(layer "F.SilkS")
		)
		(fp_line
			(start -0.7874 -0.4064)
			(end 0.7874 -0.4064)
			(stroke
				(width 0.1524)
				(type default)
			)
			(layer "F.SilkS")
		)
		(fp_line
			(start 0.7874 -0.4064)
			(end 0.7874 0.4064)
			(stroke
				(width 0.1524)
				(type default)
			)
			(layer "F.SilkS")
		)
		(fp_line
			(start -0.67945 0.3048)
			(end -0.67945 -0.305054)
			(stroke
				(width 0.1)
				(type default)
			)
			(layer "F.Fab")
		)
		(fp_line
			(start -0.12065 0.3048)
			(end -0.67945 0.3048)
			(stroke
				(width 0.1)
				(type default)
			)
			(layer "F.Fab")
		)
		(fp_line
			(start 0.120396 0.3048)
			(end 0.120396 0.2794)
			(stroke
				(width 0.1)
				(type default)
			)
			(layer "F.Fab")
		)
		(fp_line
			(start 0.67945 0.3048)
			(end 0.120396 0.3048)
			(stroke
				(width 0.1)
				(type default)
			)
			(layer "F.Fab")
		)
		(fp_line
			(start -0.12065 0.2794)
			(end -0.12065 0.3048)
			(stroke
				(width 0.1)
				(type default)
			)
			(layer "F.Fab")
		)
		(fp_line
			(start 0.120396 0.2794)
			(end -0.12065 0.2794)
			(stroke
				(width 0.1)
				(type default)
			)
			(layer "F.Fab")
		)
		(fp_line
			(start -0.12065 -0.2794)
			(end 0.12065 -0.2794)
			(stroke
				(width 0.1)
				(type default)
			)
			(layer "F.Fab")
		)
		(fp_line
			(start 0.12065 -0.2794)
			(end 0.12065 -0.3048)
			(stroke
				(width 0.1)
				(type default)
			)
			(layer "F.Fab")
		)
		(fp_line
			(start 0.12065 -0.3048)
			(end 0.67945 -0.3048)
			(stroke
				(width 0.1)
				(type default)
			)
			(layer "F.Fab")
		)
		(fp_line
			(start 0.67945 -0.3048)
			(end 0.67945 0.3048)
			(stroke
				(width 0.1)
				(type default)
			)
			(layer "F.Fab")
		)
		(fp_line
			(start -0.67945 -0.305054)
			(end -0.12065 -0.305054)
			(stroke
				(width 0.1)
				(type default)
			)
			(layer "F.Fab")
		)
		(fp_line
			(start -0.12065 -0.305054)
			(end -0.12065 -0.2794)
			(stroke
				(width 0.1)
				(type default)
			)
			(layer "F.Fab")
		)
		(pad "1" smd circle
			(at -0.40005 0 270)
			(size 0 0)
			(layers "F.Cu" "F.Mask" "F.Paste")
			(net "RST_CPU1_DRAM_GH_N")
		)
		(pad "2" smd circle
			(at 0.40005 0 270)
			(size 0 0)
			(layers "F.Cu" "F.Mask" "F.Paste")
			(net "RST_CPU1_DRAM_GH_PLD_N")
		)
	)
	(footprint ""
		(layer "F.Cu")
		(at 15.436596 -395.247876 180)
		(property "Reference" "R3268"
			(at 0 0 180)
			(layer "F.SilkS")
			(hide yes)
			(effects
				(font
					(size 1.27 1.27)
				)
			)
		)
		(property "Value" ""
			(at 0 0 180)
			(layer "F.Fab")
			(effects
				(font
					(size 1.27 1.27)
				)
			)
		)
		(duplicate_pad_numbers_are_jumpers no)
		(fp_line
			(start 0.7874 0.4064)
			(end -0.7874 0.4064)
			(stroke
				(width 0.1524)
				(type default)
			)
			(layer "F.SilkS")
		)
		(fp_line
			(start 0.7874 -0.4064)
			(end 0.7874 0.4064)
			(stroke
				(width 0.1524)
				(type default)
			)
			(layer "F.SilkS")
		)
		(fp_line
			(start -0.7874 0.4064)
			(end -0.7874 -0.4064)
			(stroke
				(width 0.1524)
				(type default)
			)
			(layer "F.SilkS")
		)
		(fp_line
			(start -0.7874 -0.4064)
			(end 0.7874 -0.4064)
			(stroke
				(width 0.1524)
				(type default)
			)
			(layer "F.SilkS")
		)
		(fp_line
			(start 0.67945 0.3048)
			(end 0.120396 0.3048)
			(stroke
				(width 0.1)
				(type default)
			)
			(layer "F.Fab")
		)
		(fp_line
			(start 0.67945 -0.3048)
			(end 0.67945 0.3048)
			(stroke
				(width 0.1)
				(type default)
			)
			(layer "F.Fab")
		)
		(fp_line
			(start 0.12065 -0.2794)
			(end 0.12065 -0.3048)
			(stroke
				(width 0.1)
				(type default)
			)
			(layer "F.Fab")
		)
		(fp_line
			(start 0.12065 -0.3048)
			(end 0.67945 -0.3048)
			(stroke
				(width 0.1)
				(type default)
			)
			(layer "F.Fab")
		)
		(fp_line
			(start 0.120396 0.3048)
			(end 0.120396 0.2794)
			(stroke
				(width 0.1)
				(type default)
			)
			(layer "F.Fab")
		)
		(fp_line
			(start 0.120396 0.2794)
			(end -0.12065 0.2794)
			(stroke
				(width 0.1)
				(type default)
			)
			(layer "F.Fab")
		)
		(fp_line
			(start -0.12065 0.3048)
			(end -0.67945 0.3048)
			(stroke
				(width 0.1)
				(type default)
			)
			(layer "F.Fab")
		)
		(fp_line
			(start -0.12065 0.2794)
			(end -0.12065 0.3048)
			(stroke
				(width 0.1)
				(type default)
			)
			(layer "F.Fab")
		)
		(fp_line
			(start -0.12065 -0.2794)
			(end 0.12065 -0.2794)
			(stroke
				(width 0.1)
				(type default)
			)
			(layer "F.Fab")
		)
		(fp_line
			(start -0.12065 -0.305054)
			(end -0.12065 -0.2794)
			(stroke
				(width 0.1)
				(type default)
			)
			(layer "F.Fab")
		)
		(fp_line
			(start -0.67945 0.3048)
			(end -0.67945 -0.305054)
			(stroke
				(width 0.1)
				(type default)
			)
			(layer "F.Fab")
		)
		(fp_line
			(start -0.67945 -0.305054)
			(end -0.12065 -0.305054)
			(stroke
				(width 0.1)
				(type default)
			)
			(layer "F.Fab")
		)
		(pad "1" smd circle
			(at -0.40005 0 180)
			(size 0 0)
			(layers "F.Cu" "F.Mask" "F.Paste")
			(net "FM_P2E_EQA1")
		)
		(pad "2" smd circle
			(at 0.40005 0 180)
			(size 0 0)
			(layers "F.Cu" "F.Mask" "F.Paste")
			(net "GND")
		)
	)
	(footprint ""
		(layer "F.Cu")
		(at 116.561616 -247.715278 90)
		(property "Reference" "C282"
			(at 0 0 90)
			(layer "F.SilkS")
			(hide yes)
			(effects
				(font
					(size 1.27 1.27)
				)
			)
		)
		(property "Value" ""
			(at 0 0 90)
			(layer "F.Fab")
			(effects
				(font
					(size 1.27 1.27)
				)
			)
		)
		(duplicate_pad_numbers_are_jumpers no)
		(fp_line
			(start 0.7874 -0.4064)
			(end 0.7874 0.4064)
			(stroke
				(width 0.1524)
				(type default)
			)
			(layer "F.SilkS")
		)
		(fp_line
			(start -0.7874 -0.4064)
			(end 0.7874 -0.4064)
			(stroke
				(width 0.1524)
				(type default)
			)
			(layer "F.SilkS")
		)
		(fp_line
			(start 0.7874 0.4064)
			(end -0.7874 0.4064)
			(stroke
				(width 0.1524)
				(type default)
			)
			(layer "F.SilkS")
		)
		(fp_line
			(start -0.7874 0.4064)
			(end -0.7874 -0.4064)
			(stroke
				(width 0.1524)
				(type default)
			)
			(layer "F.SilkS")
		)
		(fp_line
			(start -0.12065 -0.305054)
			(end -0.12065 -0.2794)
			(stroke
				(width 0.1)
				(type default)
			)
			(layer "F.Fab")
		)
		(fp_line
			(start -0.67945 -0.305054)
			(end -0.12065 -0.305054)
			(stroke
				(width 0.1)
				(type default)
			)
			(layer "F.Fab")
		)
		(fp_line
			(start 0.67945 -0.3048)
			(end 0.67945 0.3048)
			(stroke
				(width 0.1)
				(type default)
			)
			(layer "F.Fab")
		)
		(fp_line
			(start 0.12065 -0.3048)
			(end 0.67945 -0.3048)
			(stroke
				(width 0.1)
				(type default)
			)
			(layer "F.Fab")
		)
		(fp_line
			(start 0.12065 -0.2794)
			(end 0.12065 -0.3048)
			(stroke
				(width 0.1)
				(type default)
			)
			(layer "F.Fab")
		)
		(fp_line
			(start -0.12065 -0.2794)
			(end 0.12065 -0.2794)
			(stroke
				(width 0.1)
				(type default)
			)
			(layer "F.Fab")
		)
		(fp_line
			(start 0.120396 0.2794)
			(end -0.12065 0.2794)
			(stroke
				(width 0.1)
				(type default)
			)
			(layer "F.Fab")
		)
		(fp_line
			(start -0.12065 0.2794)
			(end -0.12065 0.3048)
			(stroke
				(width 0.1)
				(type default)
			)
			(layer "F.Fab")
		)
		(fp_line
			(start 0.67945 0.3048)
			(end 0.120396 0.3048)
			(stroke
				(width 0.1)
				(type default)
			)
			(layer "F.Fab")
		)
		(fp_line
			(start 0.120396 0.3048)
			(end 0.120396 0.2794)
			(stroke
				(width 0.1)
				(type default)
			)
			(layer "F.Fab")
		)
		(fp_line
			(start -0.12065 0.3048)
			(end -0.67945 0.3048)
			(stroke
				(width 0.1)
				(type default)
			)
			(layer "F.Fab")
		)
		(fp_line
			(start -0.67945 0.3048)
			(end -0.67945 -0.305054)
			(stroke
				(width 0.1)
				(type default)
			)
			(layer "F.Fab")
		)
		(pad "1" smd circle
			(at -0.40005 0 90)
			(size 0 0)
			(layers "F.Cu" "F.Mask" "F.Paste")
			(net "PVCCIN_CPU1")
		)
		(pad "2" smd circle
			(at 0.40005 0 90)
			(size 0 0)
			(layers "F.Cu" "F.Mask" "F.Paste")
			(net "GND")
		)
	)
	(footprint ""
		(layer "F.Cu")
		(at 21.176996 -99.413314 180)
		(property "Reference" "R3657"
			(at 0 0 180)
			(layer "F.SilkS")
			(hide yes)
			(effects
				(font
					(size 1.27 1.27)
				)
			)
		)
		(property "Value" ""
			(at 0 0 180)
			(layer "F.Fab")
			(effects
				(font
					(size 1.27 1.27)
				)
			)
		)
		(duplicate_pad_numbers_are_jumpers no)
		(fp_line
			(start 0.7874 0.4064)
			(end -0.7874 0.4064)
			(stroke
				(width 0.1524)
				(type default)
			)
			(layer "F.SilkS")
		)
		(fp_line
			(start 0.7874 -0.4064)
			(end 0.7874 0.4064)
			(stroke
				(width 0.1524)
				(type default)
			)
			(layer "F.SilkS")
		)
		(fp_line
			(start -0.7874 0.4064)
			(end -0.7874 -0.4064)
			(stroke
				(width 0.1524)
				(type default)
			)
			(layer "F.SilkS")
		)
		(fp_line
			(start -0.7874 -0.4064)
			(end 0.7874 -0.4064)
			(stroke
				(width 0.1524)
				(type default)
			)
			(layer "F.SilkS")
		)
		(fp_line
			(start 0.67945 0.3048)
			(end 0.120396 0.3048)
			(stroke
				(width 0.1)
				(type default)
			)
			(layer "F.Fab")
		)
		(fp_line
			(start 0.67945 -0.3048)
			(end 0.67945 0.3048)
			(stroke
				(width 0.1)
				(type default)
			)
			(layer "F.Fab")
		)
		(fp_line
			(start 0.12065 -0.2794)
			(end 0.12065 -0.3048)
			(stroke
				(width 0.1)
				(type default)
			)
			(layer "F.Fab")
		)
		(fp_line
			(start 0.12065 -0.3048)
			(end 0.67945 -0.3048)
			(stroke
				(width 0.1)
				(type default)
			)
			(layer "F.Fab")
		)
		(fp_line
			(start 0.120396 0.3048)
			(end 0.120396 0.2794)
			(stroke
				(width 0.1)
				(type default)
			)
			(layer "F.Fab")
		)
		(fp_line
			(start 0.120396 0.2794)
			(end -0.12065 0.2794)
			(stroke
				(width 0.1)
				(type default)
			)
			(layer "F.Fab")
		)
		(fp_line
			(start -0.12065 0.3048)
			(end -0.67945 0.3048)
			(stroke
				(width 0.1)
				(type default)
			)
			(layer "F.Fab")
		)
		(fp_line
			(start -0.12065 0.2794)
			(end -0.12065 0.3048)
			(stroke
				(width 0.1)
				(type default)
			)
			(layer "F.Fab")
		)
		(fp_line
			(start -0.12065 -0.2794)
			(end 0.12065 -0.2794)
			(stroke
				(width 0.1)
				(type default)
			)
			(layer "F.Fab")
		)
		(fp_line
			(start -0.12065 -0.305054)
			(end -0.12065 -0.2794)
			(stroke
				(width 0.1)
				(type default)
			)
			(layer "F.Fab")
		)
		(fp_line
			(start -0.67945 0.3048)
			(end -0.67945 -0.305054)
			(stroke
				(width 0.1)
				(type default)
			)
			(layer "F.Fab")
		)
		(fp_line
			(start -0.67945 -0.305054)
			(end -0.12065 -0.305054)
			(stroke
				(width 0.1)
				(type default)
			)
			(layer "F.Fab")
		)
		(pad "1" smd circle
			(at -0.40005 0 180)
			(size 0 0)
			(layers "F.Cu" "F.Mask" "F.Paste")
			(net "P3V3_AUX")
		)
		(pad "2" smd circle
			(at 0.40005 0 180)
			(size 0 0)
			(layers "F.Cu" "F.Mask" "F.Paste")
			(net "USB_HUB_OVCUR2")
		)
	)
	(footprint ""
		(layer "F.Cu")
		(at 157.061408 -45.462698 -90)
		(property "Reference" "R4461"
			(at 0 0 270)
			(layer "F.SilkS")
			(hide yes)
			(effects
				(font
					(size 1.27 1.27)
				)
			)
		)
		(property "Value" ""
			(at 0 0 270)
			(layer "F.Fab")
			(effects
				(font
					(size 1.27 1.27)
				)
			)
		)
		(duplicate_pad_numbers_are_jumpers no)
		(fp_line
			(start -0.7874 -0.4064)
			(end 0.7874 -0.4064)
			(stroke
				(width 0.1524)
				(type default)
			)
			(layer "F.SilkS")
		)
		(fp_line
			(start 0.7874 -0.4064)
			(end 0.7874 0.4064)
			(stroke
				(width 0.1524)
				(type default)
			)
			(layer "F.SilkS")
		)
		(fp_line
			(start -0.67945 0.3048)
			(end -0.67945 -0.305054)
			(stroke
				(width 0.1)
				(type default)
			)
			(layer "F.Fab")
		)
		(fp_line
			(start -0.12065 0.3048)
			(end -0.67945 0.3048)
			(stroke
				(width 0.1)
				(type default)
			)
			(layer "F.Fab")
		)
		(fp_line
			(start 0.120396 0.3048)
			(end 0.120396 0.2794)
			(stroke
				(width 0.1)
				(type default)
			)
			(layer "F.Fab")
		)
		(fp_line
			(start 0.67945 0.3048)
			(end 0.120396 0.3048)
			(stroke
				(width 0.1)
				(type default)
			)
			(layer "F.Fab")
		)
		(fp_line
			(start -0.12065 0.2794)
			(end -0.12065 0.3048)
			(stroke
				(width 0.1)
				(type default)
			)
			(layer "F.Fab")
		)
		(fp_line
			(start 0.120396 0.2794)
			(end -0.12065 0.2794)
			(stroke
				(width 0.1)
				(type default)
			)
			(layer "F.Fab")
		)
		(fp_line
			(start -0.12065 -0.2794)
			(end 0.12065 -0.2794)
			(stroke
				(width 0.1)
				(type default)
			)
			(layer "F.Fab")
		)
		(fp_line
			(start 0.12065 -0.2794)
			(end 0.12065 -0.3048)
			(stroke
				(width 0.1)
				(type default)
			)
			(layer "F.Fab")
		)
		(fp_line
			(start 0.12065 -0.3048)
			(end 0.67945 -0.3048)
			(stroke
				(width 0.1)
				(type default)
			)
			(layer "F.Fab")
		)
		(fp_line
			(start 0.67945 -0.3048)
			(end 0.67945 0.3048)
			(stroke
				(width 0.1)
				(type default)
			)
			(layer "F.Fab")
		)
		(fp_line
			(start -0.67945 -0.305054)
			(end -0.12065 -0.305054)
			(stroke
				(width 0.1)
				(type default)
			)
			(layer "F.Fab")
		)
		(fp_line
			(start -0.12065 -0.305054)
			(end -0.12065 -0.2794)
			(stroke
				(width 0.1)
				(type default)
			)
			(layer "F.Fab")
		)
		(pad "1" smd rect
			(at -0.40005 0 90)
			(size 0.4572 0.508)
			(layers "F.Cu" "F.Mask" "F.Paste")
			(net "USB2_HOST_PCH_0_DN")
		)
		(pad "2" smd rect
			(at 0.40005 0 90)
			(size 0.4572 0.508)
			(layers "F.Cu" "F.Mask" "F.Paste")
			(net "USB2_HUB_2_BUF_EXT_R_DN")
		)
	)
	(footprint ""
		(layer "F.Cu")
		(at 346.70619 -69.36994 90)
		(property "Reference" "C149"
			(at 0 0 90)
			(layer "F.SilkS")
			(hide yes)
			(effects
				(font
					(size 1.27 1.27)
				)
			)
		)
		(property "Value" ""
			(at 0 0 90)
			(layer "F.Fab")
			(effects
				(font
					(size 1.27 1.27)
				)
			)
		)
		(duplicate_pad_numbers_are_jumpers no)
		(fp_line
			(start 0.299974 -0.150114)
			(end 0.299974 0.150114)
			(stroke
				(width 0.1)
				(type default)
			)
			(layer "F.Fab")
		)
		(fp_line
			(start -0.299974 -0.150114)
			(end 0.299974 -0.150114)
			(stroke
				(width 0.1)
				(type default)
			)
			(layer "F.Fab")
		)
		(fp_line
			(start 0.299974 0.150114)
			(end -0.299974 0.150114)
			(stroke
				(width 0.1)
				(type default)
			)
			(layer "F.Fab")
		)
		(fp_line
			(start -0.299974 0.150114)
			(end -0.299974 -0.150114)
			(stroke
				(width 0.1)
				(type default)
			)
			(layer "F.Fab")
		)
		(pad "1" smd rect
			(at -0.2667 0 90)
			(size 0.3048 0.381)
			(layers "F.Cu" "F.Mask" "F.Paste")
			(net "DMI_CPU0_PCH_TX_C_DN<2>")
		)
		(pad "2" smd rect
			(at 0.2667 0 90)
			(size 0.3048 0.381)
			(layers "F.Cu" "F.Mask" "F.Paste")
			(net "DMI_CPU0_PCH_TX_DN<2>")
		)
		(zone
			(layer "In1.Cu")
			(hatch none 0.5)
			(connect_pads
				(clearance 0)
			)
			(min_thickness 0.25)
			(keepout
				(tracks not_allowed)
				(vias allowed)
				(pads allowed)
				(copperpour not_allowed)
				(footprints allowed)
			)
			(placement
				(enabled no)
				(sheetname "")
			)
			(fill
				(thermal_gap 0.5)
				(thermal_bridge_width 0.5)
				(island_removal_mode 0)
			)
			(polygon
				(pts
					(arc
						(start 346.94749 -69.50964)
						(mid 346.925172 -69.455758)
						(end 346.87129 -69.43344)
					)
					(arc
						(start 346.54109 -69.43344)
						(mid 346.487208 -69.455758)
						(end 346.46489 -69.50964)
					)
					(arc
						(start 346.46489 -69.76364)
						(mid 346.487208 -69.817522)
						(end 346.54109 -69.83984)
					)
					(arc
						(start 346.87129 -69.83984)
						(mid 346.925172 -69.817522)
						(end 346.94749 -69.76364)
					)
				)
			)
		)
		(zone
			(layer "In1.Cu")
			(hatch none 0.5)
			(connect_pads
				(clearance 0)
			)
			(min_thickness 0.25)
			(keepout
				(tracks not_allowed)
				(vias allowed)
				(pads allowed)
				(copperpour not_allowed)
				(footprints allowed)
			)
			(placement
				(enabled no)
				(sheetname "")
			)
			(fill
				(thermal_gap 0.5)
				(thermal_bridge_width 0.5)
				(island_removal_mode 0)
			)
			(polygon
				(pts
					(arc
						(start 346.94749 -68.97624)
						(mid 346.925172 -68.922358)
						(end 346.87129 -68.90004)
					)
					(arc
						(start 346.54109 -68.90004)
						(mid 346.487208 -68.922358)
						(end 346.46489 -68.97624)
					)
					(arc
						(start 346.46489 -69.23024)
						(mid 346.487208 -69.284122)
						(end 346.54109 -69.30644)
					)
					(arc
						(start 346.87129 -69.30644)
						(mid 346.925172 -69.284122)
						(end 346.94749 -69.23024)
					)
				)
			)
		)
	)
)
